FILE_TYPE = CONNECTIVITY;
{Allegro Design Entry HDL 16.6-p007 (v16-6-112F) 10/10/2012}
"PAGE_NUMBER" = 101;
0"NC";
1"P3V3_STBY_MNG\g";
2"P3V3_STBY_MNG_RGMII\g"VOLTAGE"+3.3V";
3"P3V3_STBY_MNG\g";
4"P3V3_STBY_MNG_RMII\g"VOLTAGE"+3.3V";
5"GND\g";
6"GND\g";
7"P3V3_STBY\g";
8"P3V3_STBY_MNG\g";
9"P3V3_STBY_MNG\g";
10"P3V3_STBY_MNG_RGMII\g";
11"P3V3_STBY_MNG_RMII\g";
12"P3V3_STBY_MNG_CPU\g";
13"P3V3_STBY_MNG\g"VOLTAGE"+3.3V";
14"P3V3_STBY_MNG_CPU\g"VOLTAGE"+3.3V";
15"GND\g";
16"GND\g";
17"GND\g";
18"GND\g";
19"GND\g";
20"GND\g";
21"GND\g";
22"GND\g";
23"CLK_25M_BMC_R";
24"CLK_25M_BMC";
25"CLK_50M_CKMNG_SPRVLLE_R";
26"CLK_50M_CKMNG_BMC_2_R";
27"TP_CLK_125M";
28"CLK_50M_CKMNG_OCP_R";
29"CLK_50M_CKMNG_SPRVLLE";
30"CLK_50M_CKMNG_BMC_2";
31"CLK_50M_CKMNG_BMC_1_R";
32"CLK_50M_CKMNG_BMC_1";
33"CLK_50M_CKMNG_PCH_10GBE";
34"CLK_50M_CKMNG_OCP";
35"PWRGD_P3V3_STBY";
36"XTAL_CK_MNG_IN";
37"XTAL_CK_MNG_OUT";
38"PD_CKMNG_OE";
39"XTAL_CK_MNG_OUT_R";
40"CLK_25M_CPLD_R";
41"A_COMP_CKMNG";
42"SMB_HOST_STBY_LVC3_SDA_R4";
43"SMB_HOST_STBY_LVC3_SCL_R4";
44"SMB_HOST_STBY_LVC3_SCL";
45"SMB_HOST_STBY_LVC3_SDA";
46"TP_CLK_125M_BMCA";
47"TP_CLK5_50M_CKMNG";
48"PU_33P_33M_SMBADR";
49"CLK_32K_SUSCLK_PLD_R";
50"CLK_50M_CKMNG_PCH_10GBE_R";
51"CLK_25M_CPLD";
52"CLK_32K_SUSCLK_PLD";
53"TP_CLK_96M_CKMNG_N";
54"TP_CLK_96M_CKMNG_P";
55"TP_CLK_100M_R_DN";
56"TP_CLK_100M_R_DP";
%"VCC_CORE"
"1","(-4500,4350)","0","mstr_symbols","I100";
;
HDL_POWER"P3V3_STBY_MNG"
VOLTAGE"5"
CDS_LIB"mstr_symbols";
"A"1;
%"VCC_CORE"
"1","(-3625,4275)","0","mstr_symbols","I101";
;
HDL_POWER"P3V3_STBY_MNG_RGMII"
VOLTAGE"3.3"
CDS_LIB"mstr_symbols";
"A"2;
%"VCC_CORE"
"1","(-3000,4375)","0","mstr_symbols","I102";
;
HDL_POWER"P3V3_STBY_MNG"
CDS_LIB"mstr_symbols"
VOLTAGE"5";
"A"3;
%"VCC_CORE"
"1","(-1900,4350)","0","mstr_symbols","I103";
;
HDL_POWER"P3V3_STBY_MNG_RMII"
CDS_LIB"mstr_symbols"
VOLTAGE"3.3";
"A"4;
%"CAP_A"
"1","(-5550,3975)","0","dev_discrete","I104";
;
PACK_TYPE"0402V"
MATERIAL"X7R"
VOLTAGE"25V"
TOLERANCE"10%"
VALUE"0.01UF"
PART_NUMBER"A36096-045"
LOCATION"C2T18"
ROOM"SYS_CLOCK"
$SEC"1"
CDS_SEC"1"
CDS_LIB"dev_discrete"
BOM_COST"SM_CONTROLLER"
CDS_LOCATION"C2T18";
"B"
$PN"2"5;
"A"
$PN"1"12;
%"RES"
"1","(-5825,4150)","0","mstr_discrete","I105";
;
CDS_SEC"1"
PART_NUMBER"G22026-127"
WATTAGE"1/10W"
MATERIAL"CHIP"
PACK_TYPE"0603"
TOLERANCE"1.0%"
VALUE"2.2"
LOCATION"R2T21"
ROOM"SYS_CLOCK"
CDS_LOCATION"R2T21"
SEC"1"
CDS_LIB"mstr_discrete"
BOM_COST"SM_CONTROLLER"
SEC_TYPE"0603";
"B"
$PN"2"12;
"A"
$PN"1"9;
%"CAP_A"
"1","(-5150,3975)","0","dev_discrete","I106";
;
TOLERANCE"10%"
VOLTAGE"6.3V"
VALUE"1.0UF"
LOCATION"C2T19"
PART_NUMBER"D97712-004"
PACK_TYPE"0402V"
MATERIAL"X6S"
ROOM"SYS_CLOCK"
$SEC"1"
CDS_SEC"1"
CDS_LIB"dev_discrete"
BOM_COST"SM_CONTROLLER"
CDS_LOCATION"C2T19";
"B"
$PN"2"5;
"A"
$PN"1"12;
%"GND"
"1","(-5150,3650)","0","mstr_symbols","I107";
;
HDL_POWER"GND"
BODY_TYPE"PLUMBING"
ROOM"SYS_CLOCK"
BOM_COST"SM_CONTROLLER"
CDS_LIB"mstr_symbols"
SIZE"1B"
VOLTAGE"0.0V";
"A\NAC"5;
%"GND"
"1","(-6600,3625)","0","mstr_symbols","I108";
;
HDL_POWER"GND"
BODY_TYPE"PLUMBING"
ROOM"SYS_CLOCK"
SIZE"1B"
CDS_LIB"mstr_symbols"
BOM_COST"SM_CONTROLLER"
VOLTAGE"0.0V";
"A\NAC"6;
%"CAP_A"
"1","(-6600,3975)","0","dev_discrete","I109";
;
PART_NUMBER"A36096-030"
MATERIAL"X7R"
VOLTAGE"16V"
TOLERANCE"10%"
VALUE"0.1UF"
LOCATION"C2T34"
PACK_TYPE"0402V"
SEC"1"
SEC_TYPE"0402V"
CDS_SEC"1"
CDS_LIB"dev_discrete"
BOM_COST"SM_CONTROLLER"
CDS_LOCATION"C2T34"
ROOM"SYS_CLOCK";
"B"
$PN"2"6;
"A"
$PN"1"8;
%"CAP_A"
"1","(-6900,3975)","0","dev_discrete","I110";
;
LOCATION"C2T30"
VALUE"0.1UF"
VOLTAGE"16V"
PACK_TYPE"0402V"
PART_NUMBER"A36096-030"
MATERIAL"X7R"
TOLERANCE"10%"
$SEC"1"
CDS_SEC"1"
CDS_LIB"dev_discrete"
BOM_COST"SM_CONTROLLER"
CDS_LOCATION"C2T30"
ROOM"SYS_CLOCK";
"B"
$PN"2"6;
"A"
$PN"1"8;
%"CAP_A"
"1","(-7300,3975)","0","dev_discrete","I111";
;
PACK_TYPE"0402V"
MATERIAL"X7R"
VOLTAGE"16V"
TOLERANCE"10%"
VALUE"0.1UF"
PART_NUMBER"A36096-030"
LOCATION"C2T25"
$SEC"1"
CDS_SEC"1"
CDS_LIB"dev_discrete"
BOM_COST"SM_CONTROLLER"
CDS_LOCATION"C2T25"
ROOM"SYS_CLOCK";
"B"
$PN"2"6;
"A"
$PN"1"8;
%"CAP_A"
"1","(-7600,3975)","0","dev_discrete","I112";
;
PACK_TYPE"0402V"
MATERIAL"X7R"
VOLTAGE"16V"
TOLERANCE"10%"
VALUE"0.1UF"
PART_NUMBER"A36096-030"
LOCATION"C2T17"
$SEC"1"
CDS_SEC"1"
CDS_LIB"dev_discrete"
BOM_COST"SM_CONTROLLER"
CDS_LOCATION"C2T17"
ROOM"SYS_CLOCK";
"B"
$PN"2"6;
"A"
$PN"1"8;
%"CAP"
"1","(-7900,3975)","0","mstr_discrete","I113";
;
CDS_SEC"1"
PART_NUMBER"C95333-007"
PACK_TYPE"0805"
MATERIAL"X6S"
VOLTAGE"16V"
TOLERANCE"10%"
VALUE"10UF"
LOCATION"C2T22"
ROOM"SYS_CLOCK"
CDS_LOCATION"C2T22"
SEC"1"
SEC_TYPE"0805"
BOM_COST"SM_CONTROLLER"
CDS_LIB"mstr_discrete";
"A"
$PN"1"8;
"B"
$PN"2"6;
%"FERRITE"
"1","(-8125,4125)","0","mstr_discrete","I114";
;
PART_NUMBER"656554-043"
MATERIAL"FB"
PACK_TYPE"SMLF"
VALUE"600"
LOCATION"FB2T2"
ROOM"SYS_CLOCK"
CDS_LOCATION"FB2T2"
$SEC"1"
CDS_SEC"1"
CDS_LIB"mstr_discrete"
BOM_COST"SM_CONTROLLER";
"A"
$PN"1"7;
"B"
$PN"2"8;
%"P3V3_STBY"
"1","(-8475,4350)","0","mstr_symbols","I115";
;
HDL_POWER"P3V3_STBY"
BODY_TYPE"PLUMBING"
CDS_LIB"mstr_symbols"
SIZE"1B"
VOLTAGE"3.3";
"G\NAC"7;
%"CAP_A"
"1","(-8475,3950)","0","dev_discrete","I116";
;
LOCATION"C2T28"
TOLERANCE"10%"
MATERIAL"X6S"
VOLTAGE"6.3V"
PACK_TYPE"0402V"
VALUE"1.0UF"
PART_NUMBER"D97712-004"
ROOM"SYS_CLOCK"
$SEC"1"
CDS_SEC"1"
CDS_LIB"dev_discrete"
BOM_COST"SM_CONTROLLER"
CDS_LOCATION"C2T28";
"B"
$PN"2"19;
"A"
$PN"1"7;
%"VCC_CORE"
"1","(-6600,4275)","0","mstr_symbols","I117";
;
HDL_POWER"P3V3_STBY_MNG"
CDS_LIB"mstr_symbols"
VOLTAGE"5";
"A"8;
%"VCC_CORE"
"1","(-6100,4350)","0","mstr_symbols","I118";
;
HDL_POWER"P3V3_STBY_MNG"
CDS_LIB"mstr_symbols"
VOLTAGE"5";
"A"9;
%"VCC_CORE"
"1","(-6300,3225)","0","mstr_symbols","I119";
;
HDL_POWER"P3V3_STBY_MNG_RGMII"
CDS_LIB"mstr_symbols"
VOLTAGE"3.3";
"A"10;
%"VCC_CORE"
"1","(-6600,3025)","0","mstr_symbols","I120";
;
HDL_POWER"P3V3_STBY_MNG_RMII"
CDS_LIB"mstr_symbols"
VOLTAGE"3.3";
"A"11;
%"VCC_CORE"
"1","(-5150,4300)","0","mstr_symbols","I121";
;
HDL_POWER"P3V3_STBY_MNG_CPU"
CDS_LIB"mstr_symbols"
VOLTAGE"3.3";
"A"12;
%"VCC_CORE"
"1","(-7000,2525)","0","mstr_symbols","I122";
;
HDL_POWER"P3V3_STBY_MNG"
CDS_LIB"mstr_symbols"
VOLTAGE"5";
"A"13;
%"VCC_CORE"
"1","(-7500,2400)","0","mstr_symbols","I123";
;
HDL_POWER"P3V3_STBY_MNG_CPU"
CDS_LIB"mstr_symbols"
VOLTAGE"3.3";
"A"14;
%"RES"
"1","(-3050,1550)","0","mstr_discrete","I124";
;
CDS_SEC"1"
TOLERANCE"1.0%"
PART_NUMBER"G21796-250"
WATTAGE"1/16W"
PACK_TYPE"0402"
VALUE"22.1"
LOCATION"R2T42"
MATERIAL"CHIP"
ROOM"SYS_CLOCK"
CDS_LOCATION"R2T42"
SEC"1"
SEC_TYPE"0402"
CDS_LIB"mstr_discrete"
BOM_COST"SM_CONTROLLER";
"B"
$PN"2"34;
"A"
$PN"1"28;
%"RES"
"1","(-3050,1700)","0","mstr_discrete","I125";
;
CDS_SEC"1"
LOCATION"R2T46"
MATERIAL"CHIP"
TOLERANCE"1.0%"
PART_NUMBER"G21796-250"
WATTAGE"1/16W"
PACK_TYPE"0402"
VALUE"22.1"
ROOM"SYS_CLOCK"
CDS_LOCATION"R2T46"
SEC"1"
BOM_COST"SM_CONTROLLER"
CDS_LIB"mstr_discrete"
SEC_TYPE"0402";
"B"
$PN"2"32;
"A"
$PN"1"31;
%"RES"
"1","(-3050,2600)","0","mstr_discrete","I130";
;
CDS_SEC"1"
PART_NUMBER"G21796-074"
VALUE"33.2"
WATTAGE"1/16W"
TOLERANCE"1%"
PACK_TYPE"0402"
LOCATION"R2T47"
MATERIAL"CHIP"
SEC_TYPE"0402"
CDS_LIB"mstr_discrete"
BOM_COST"SM_CONTROLLER"
SEC"1"
CDS_LOCATION"R2T47"
ROOM"SYS_CLOCK";
"B"
$PN"2"51;
"A"
$PN"1"40;
%"RES"
"1","(-7125,1950)","0","mstr_discrete","I134";
;
CDS_SEC"1"
CDS_LOCATION"R1W22"
PART_NUMBER"G21497-005"
TOLERANCE"5%"
WATTAGE"1/16W"
VALUE"0.0"
LOCATION"R1W22"
MATERIAL"CHIP"
PACK_TYPE"0402"
CDS_LIB"mstr_discrete"
ROOM"IO_SLOT"
SEC"1"
SEC_TYPE"0402";
"B"
$PN"2"43;
"A"
$PN"1"44;
%"RES"
"1","(-7125,1825)","0","mstr_discrete","I135";
;
CDS_SEC"1"
CDS_LOCATION"R1W23"
TOLERANCE"5%"
PART_NUMBER"G21497-005"
WATTAGE"1/16W"
VALUE"0.0"
LOCATION"R1W23"
MATERIAL"CHIP"
PACK_TYPE"0402"
SEC_TYPE"0402"
SEC"1"
ROOM"IO_SLOT"
CDS_LIB"mstr_discrete";
"B"
$PN"2"42;
"A"
$PN"1"45;
%"RES"
"1","(-6925,1250)","0","mstr_discrete","I138";
;
CDS_SEC"1"
CDS_LOCATION"R1W24"
PART_NUMBER"G21497-005"
MATERIAL"CHIP"
WATTAGE"1/16W"
PACK_TYPE"0402"
VALUE"0.0"
TOLERANCE"5%"
LOCATION"R1W24"
SEC_TYPE"0402"
SEC"1"
ROOM"IO_SLOT"
CDS_LIB"mstr_discrete";
"B"
$PN"2"39;
"A"
$PN"1"37;
%"CAP"
"1","(-1900,4000)","0","mstr_discrete","I139";
;
CDS_SEC"1"
CDS_LOCATION"C1W17"
MATERIAL"EMPTY"
TOLERANCE"10%"
LOCATION"C1W17"
VALUE"10UF"
PACK_TYPE"0805"
VOLTAGE"16V"
PART_NUMBER"C95333-007"
SEC_TYPE"0805"
SEC"1"
CDS_LIB"mstr_discrete";
"A"
$PN"1"4;
"B"
$PN"2"22;
%"RES"
"2","(-8325,1400)","0","mstr_discrete","I140";
;
CDS_SEC"1"
WATTAGE"1/16W"
MATERIAL"CHIP"
PACK_TYPE"0402"
TOLERANCE"1%"
VALUE"1.00K"
LOCATION"R1W25"
PART_NUMBER"G21796-026"
ROOM"SYS_CLOCK"
SEC"1"
SEC_TYPE"0402"
BOM_COST"SM_CONTROLLER"
CDS_LIB"mstr_discrete"
CDS_LOCATION"R1W25";
"A"
$PN"1"48;
"B"
$PN"2"15;
%"GND"
"1","(-8325,1125)","0","mstr_symbols","I141";
;
HDL_POWER"GND"
BODY_TYPE"PLUMBING"
ROOM"SYS_CLOCK"
BOM_COST"SM_CONTROLLER"
SIZE"1B"
CDS_LIB"mstr_symbols"
VOLTAGE"0.0V";
"A\NAC"15;
%"RES"
"1","(-3050,2775)","0","mstr_discrete","I142";
;
CDS_SEC"1"
PACK_TYPE"0402"
TOLERANCE"1%"
MATERIAL"CHIP"
WATTAGE"1/16W"
LOCATION"R8F27"
PART_NUMBER"G21796-074"
VALUE"33.2"
CDS_LOCATION"R8F27"
SEC_TYPE"0402"
CDS_LIB"mstr_discrete"
BOM_COST"SM_CONTROLLER"
SEC"1"
ROOM"SYS_CLOCK";
"B"
$PN"2"52;
"A"
$PN"1"49;
%"RES"
"1","(-3050,2150)","0","mstr_discrete","I143";
;
CDS_SEC"1"
VALUE"22.1"
TOLERANCE"1.0%"
PACK_TYPE"0402"
LOCATION"R8G24"
WATTAGE"1/16W"
PART_NUMBER"G21796-250"
MATERIAL"CHIP"
CDS_LOCATION"R8G24"
SEC_TYPE"0402"
CDS_LIB"mstr_discrete"
BOM_COST"SM_CONTROLLER"
SEC"1"
ROOM"SYS_CLOCK";
"B"
$PN"2"33;
"A"
$PN"1"50;
%"RES"
"1","(-3050,2000)","0","mstr_discrete","I144";
;
CDS_SEC"1"
VALUE"22.1"
TOLERANCE"1.0%"
PACK_TYPE"0402"
LOCATION"R8G25"
WATTAGE"1/16W"
PART_NUMBER"G21796-250"
MATERIAL"CHIP"
GROUP"NI_I210&RJ45"
CDS_LOCATION"R8G25"
SEC_TYPE"0402"
CDS_LIB"mstr_discrete"
BOM_COST"SM_CONTROLLER"
SEC"1"
ROOM"SYS_CLOCK";
"B"
$PN"2"29;
"A"
$PN"1"25;
%"RES"
"1","(-3050,1850)","0","mstr_discrete","I145";
;
CDS_SEC"1"
WATTAGE"1/16W"
TOLERANCE"1.0%"
MATERIAL"CHIP"
LOCATION"R8G1"
PART_NUMBER"G21796-250"
PACK_TYPE"0402"
VALUE"22.1"
CDS_LOCATION"R8G1"
SEC_TYPE"0402"
CDS_LIB"mstr_discrete"
BOM_COST"SM_CONTROLLER"
SEC"1"
ROOM"SYS_CLOCK";
"B"
$PN"2"30;
"A"
$PN"1"26;
%"CAP"
"1","(-7600,800)","0","mstr_discrete","I146";
;
CDS_SEC"1"
MATERIAL"COG"
TOLERANCE"5%"
VOLTAGE"50V"
PART_NUMBER"A36095-047"
PACK_TYPE"0402LF"
VALUE"15.0PF"
LOCATION"C8F19"
SEC_TYPE"0402LF"
SEC"1"
CDS_LIB"mstr_discrete"
ROOM"SB"
BOM_COST"SYS_CLOCK"
CDS_LOCATION"C8F19";
"A"
$PN"1"37;
"B"
$PN"2"18;
%"CAP"
"1","(-7150,800)","0","mstr_discrete","I147";
;
CDS_SEC"1"
MATERIAL"COG"
TOLERANCE"5%"
VOLTAGE"50V"
VALUE"15.0PF"
LOCATION"C8F18"
PART_NUMBER"A36095-047"
PACK_TYPE"0402LF"
SEC_TYPE"0402LF"
SEC"1"
CDS_LIB"mstr_discrete"
ROOM"SB"
BOM_COST"SYS_CLOCK"
CDS_LOCATION"C8F18";
"A"
$PN"1"36;
"B"
$PN"2"18;
%"RES"
"1","(-3050,2450)","0","mstr_discrete","I20";
;
CDS_SEC"1"
LOCATION"R8F29"
TOLERANCE"1%"
VALUE"33.2"
MATERIAL"CHIP"
WATTAGE"1/16W"
PACK_TYPE"0402"
PART_NUMBER"G21796-074"
ROOM"SYS_CLOCK"
CDS_LOCATION"R8F29"
SEC"1"
CDS_LIB"mstr_discrete"
SEC_TYPE"0402"
BOM_COST"SM_CONTROLLER";
"B"
$PN"2"24;
"A"
$PN"1"23;
%"RES"
"2","(-4375,3000)","2","mstr_discrete","I28";
;
TOLERANCE"1%"
MATERIAL"CHIP"
WATTAGE"1/16W"
VALUE"475.0"
LOCATION"R8F25"
PART_NUMBER"G21796-077"
PACK_TYPE"0402"
ROOM"SYS_CLOCK"
CDS_LOCATION"R8F25"
$SEC"1"
CDS_SEC"1"
BOM_COST"SM_CONTROLLER"
CDS_LIB"mstr_discrete";
"A"
$PN"1"41;
"B"
$PN"2"16;
%"GND"
"1","(-4375,2800)","0","mstr_symbols","I29";
;
HDL_POWER"GND"
BODY_TYPE"PLUMBING"
ROOM"SYS_CLOCK"
BOM_COST"SM_CONTROLLER"
SIZE"1B"
CDS_LIB"mstr_symbols"
VOLTAGE"0.0V";
"A\NAC"16;
%"GND"
"1","(-4650,800)","0","mstr_symbols","I33";
;
HDL_POWER"GND"
BODY_TYPE"PLUMBING"
ROOM"SYS_CLOCK"
SIZE"1B"
CDS_LIB"mstr_symbols"
BOM_COST"SM_CONTROLLER"
VOLTAGE"0.0V";
"A\NAC"17;
%"ICS9FGP204"
"1","(-5500,1850)","0","mstr_clock","I34";
;
CDS_SEC"1"
PART_NUMBER"E95226-001"
LOCATION"EU8F2"
MATERIAL"IC"
PACK_TYPE"MLFP"
BOM_COST"SM_CONTROLLER"
CDS_LIB"mstr_clock"
CDS_LMAN_SYM_OUTLINE"-600,900,600,-900"
SEC_TYPE"MLFP"
SEC"1"
CDS_LOCATION"EU8F2"
ROOM"SYS_CLOCK";
"RGMII<1>"
$PN"36"27;
"RGMII<0>"
$PN"37"46;
"GND_RGMII"
$PN"35"17;
"VDD_RGMII"
$PN"34"10;
"SMBDAT"
$PN"39"42;
"X2_25"
$PN"20"39;
"SMBCLK"
$PN"38"43;
"VTTPWR_GD_PD_N"
$PN"40"35;
"VDDCPU"
$PN"9"14;
"GNDCPU"
$PN"10"17;
"OE_CPU"
$PN"6"38;
"VDD96"
$PN"2"13;
"OE_96"
$PN"5"38;
"VDD33"
$PN"23"13;
"33MHZ_SMBADR"
$PN"22"48;
"GNDRMII<1>"
$PN"30"17;
"VDDRMII<1>"
$PN"31"11;
"VDDRMII<0>"
$PN"26"11;
"GNDRMII<0>"
$PN"27"17;
"X1_25"
$PN"19"36;
"IREF"
$PN"11"41;
"VDDREF"
$PN"15"13;
"CPUCLKT0"
$PN"7"56;
"GNDREF"
$PN"18"17;
"CPUCLKC0"
$PN"8"55;
"DOT96SST"
$PN"3"54;
"DOT96SSC"
$PN"4"53;
"GND<0>"
$PN"1"17;
"GND33"
$PN"21"17;
"GND<1>"
$PN"41"17;
"RMII<0>"
$PN"33"28;
"RMII<3>"
$PN"28"25;
"RMII<4>"
$PN"25"50;
"RMII<5>"
$PN"24"47;
"RMII<2>"
$PN"29"26;
"RMII<1>"
$PN"32"31;
"25MHZ_1"
$PN"17"40;
"25MHZ_0"
$PN"16"23;
"GND32K"
$PN"14"17;
"32KHZ"
$PN"13"49;
"VDD32K"
$PN"12"13;
%"RES"
"2","(-7925,1225)","0","mstr_discrete","I48";
;
CDS_SEC"1"
PART_NUMBER"G21796-026"
VALUE"1.00K"
PACK_TYPE"0402"
WATTAGE"1/16W"
LOCATION"R2T25"
MATERIAL"CHIP"
TOLERANCE"1%"
CDS_LIB"mstr_discrete"
BOM_COST"SM_CONTROLLER"
SEC_TYPE"0402"
SEC"1"
CDS_LOCATION"R2T25"
ROOM"SYS_CLOCK";
"A"
$PN"1"38;
"B"
$PN"2"20;
%"CRYSTAL"
"3","(-7350,1050)","2","mstr_discrete","I52";
;
PART_NUMBER"D71700-033"
VALUE"25.000MHZ"
LOCATION"Y8F1"
MATERIAL"IC"
POWER_GROUP"GND=GND"
PACK_TYPE"2013LF"
BOM_COST"SM_CONTROLLER"
CDS_LIB"mstr_discrete"
CDS_SEC"1"
$SEC"1"
CDS_LOCATION"Y8F1"
ROOM"SYS_CLOCK";
"A"
$PN"1"36;
"B"
$PN"3"37;
%"GND"
"1","(-7350,400)","0","mstr_symbols","I54";
;
HDL_POWER"GND"
BODY_TYPE"PLUMBING"
VOLTAGE"0.0V"
CDS_LIB"mstr_symbols"
SIZE"1B"
BOM_COST"SM_CONTROLLER"
ROOM"SYS_CLOCK";
"A\NAC"18;
%"GND"
"1","(-8475,3650)","0","mstr_symbols","I58";
;
HDL_POWER"GND"
BODY_TYPE"PLUMBING"
ROOM"SYS_CLOCK"
SIZE"1B"
CDS_LIB"mstr_symbols"
BOM_COST"SM_CONTROLLER"
VOLTAGE"0.0V";
"A\NAC"19;
%"GND"
"1","(-7925,900)","0","mstr_symbols","I64";
;
HDL_POWER"GND"
BODY_TYPE"PLUMBING"
VOLTAGE"0.0V"
CDS_LIB"mstr_symbols"
SIZE"1B"
BOM_COST"SM_CONTROLLER"
ROOM"SYS_CLOCK";
"A\NAC"20;
%"CAP_A"
"1","(-3625,3925)","0","dev_discrete","I89";
;
MATERIAL"X6S"
PACK_TYPE"0402V"
PART_NUMBER"D97712-004"
LOCATION"C2T31"
VALUE"1.0UF"
VOLTAGE"6.3V"
TOLERANCE"10%"
CDS_LOCATION"C2T31"
BOM_COST"SM_CONTROLLER"
CDS_LIB"dev_discrete"
CDS_SEC"1"
$SEC"1"
ROOM"SYS_CLOCK";
"B"
$PN"2"21;
"A"
$PN"1"2;
%"CAP_A"
"1","(-4050,3925)","0","dev_discrete","I90";
;
PART_NUMBER"A36096-045"
PACK_TYPE"0402V"
LOCATION"C2T27"
VALUE"0.01UF"
TOLERANCE"10%"
VOLTAGE"25V"
MATERIAL"X7R"
CDS_LOCATION"C2T27"
BOM_COST"SM_CONTROLLER"
CDS_LIB"dev_discrete"
CDS_SEC"1"
$SEC"1"
ROOM"SYS_CLOCK";
"B"
$PN"2"21;
"A"
$PN"1"2;
%"RES"
"1","(-4325,4150)","0","mstr_discrete","I94";
;
LOCATION"R2T23"
PART_NUMBER"G22026-127"
VALUE"2.2"
TOLERANCE"1.0%"
PACK_TYPE"0603"
MATERIAL"CHIP"
WATTAGE"1/10W"
CDS_LIB"mstr_discrete"
BOM_COST"SM_CONTROLLER"
CDS_SEC"1"
$SEC"1"
CDS_LOCATION"R2T23"
ROOM"SYS_CLOCK";
"B"
$PN"2"2;
"A"
$PN"1"1;
%"RES"
"1","(-2825,4200)","0","mstr_discrete","I95";
;
PACK_TYPE"0603"
MATERIAL"CHIP"
TOLERANCE"1.0%"
PART_NUMBER"G22026-127"
VALUE"2.2"
WATTAGE"1/10W"
LOCATION"R2T52"
ROOM"SYS_CLOCK"
CDS_LOCATION"R2T52"
$SEC"1"
CDS_SEC"1"
CDS_LIB"mstr_discrete"
BOM_COST"SM_CONTROLLER";
"B"
$PN"2"4;
"A"
$PN"1"3;
%"GND"
"1","(-3625,3625)","0","mstr_symbols","I96";
;
HDL_POWER"GND"
BODY_TYPE"PLUMBING"
VOLTAGE"0.0V"
SIZE"1B"
CDS_LIB"mstr_symbols"
BOM_COST"SM_CONTROLLER"
ROOM"SYS_CLOCK";
"A\NAC"21;
%"CAP_A"
"1","(-2250,4000)","0","dev_discrete","I97";
;
PART_NUMBER"D97712-004"
LOCATION"C2T38"
VALUE"1.0UF"
PACK_TYPE"0402V"
VOLTAGE"6.3V"
MATERIAL"X6S"
TOLERANCE"10%"
ROOM"SYS_CLOCK"
$SEC"1"
CDS_SEC"1"
CDS_LIB"dev_discrete"
BOM_COST"SM_CONTROLLER"
CDS_LOCATION"C2T38";
"B"
$PN"2"22;
"A"
$PN"1"4;
%"GND"
"1","(-1900,3650)","0","mstr_symbols","I98";
;
HDL_POWER"GND"
BODY_TYPE"PLUMBING"
VOLTAGE"0.0V"
CDS_LIB"mstr_symbols"
SIZE"1B"
BOM_COST"SM_CONTROLLER"
ROOM"SYS_CLOCK";
"A\NAC"22;
%"CAP_A"
"1","(-2625,4000)","0","dev_discrete","I99";
;
MATERIAL"X7R"
VALUE"0.01UF"
VOLTAGE"25V"
TOLERANCE"10%"
PACK_TYPE"0402V"
LOCATION"C2T37"
PART_NUMBER"A36096-045"
ROOM"SYS_CLOCK"
$SEC"1"
CDS_SEC"1"
CDS_LIB"dev_discrete"
BOM_COST"SM_CONTROLLER"
CDS_LOCATION"C2T37";
"B"
$PN"2"22;
"A"
$PN"1"4;
END.
